# BASEBOARD_FAB2 (Tioga Pass) — schematic netlist excerpt (pin names and nets, part order shuffled) for the footprints in the layout excerpt that follows; sources: Cadence DE-HDL packaged netlist, KiCad conversion of Wiwynn_Tioga_Pass_MB.brd

RT28  RES  0 5.0% CHIP  pkg 0603  page 203 : A = VR_PVCCIN_CPU0_PH4_BOOT ; B = VR_PVCCIN_CPU0_PH4_BOOT_R
R25W104  RES  4.75K 1% CHIP  pkg 0402  page 150 : A = P3V3_STBY ; B = BMC_STRAP_BIT27
R4D54  RES  0.0 5% CHIP  pkg 0402  page 213 : A = SVID_DIO0_CPU1_R ; B = SVID_VDIO_PVCCIO_CPU1

(kicad_pcb
	(version 20260206)
	(generator "pcbnew")
	(generator_version "10.0")
	(general
		(thickness 1.6)
		(legacy_teardrops no)
	)
	(paper "A4")
	(title_block
		(title "Wiwynn_Tioga_Pass_MB.brd")
		(comment 1 "Tioga Pass / footprints 58-60 of 4770")
	)
	(layers
		(0 "F.Cu" signal "TOP")
		(4 "In1.Cu" signal "L2GND")
		(6 "In2.Cu" signal "L3")
		(8 "In3.Cu" signal "L4GND")
		(10 "In4.Cu" signal "L5")
		(12 "In5.Cu" signal "L6GND")
		(14 "In6.Cu" signal "L7VCC")
		(16 "In7.Cu" signal "L8VCC")
		(18 "In8.Cu" signal "L9GND")
		(20 "In9.Cu" signal "L10")
		(22 "In10.Cu" signal "L11GND")
		(24 "In11.Cu" signal "L12")
		(26 "In12.Cu" signal "L13GND")
		(2 "B.Cu" signal "BOTTOM")
		(9 "F.Adhes" user "F.Adhesive")
		(11 "B.Adhes" user "B.Adhesive")
		(13 "F.Paste" user "Package Geometry/Pastemask Top")
		(15 "B.Paste" user "Package Geometry/Pastemask Bottom")
		(5 "F.SilkS" user "Ref Des/Silkscreen Top")
		(7 "B.SilkS" user "Ref Des/Silkscreen Bottom")
		(1 "F.Mask" user "Board Geometry/Soldermask Top")
		(3 "B.Mask" user "Board Geometry/Soldermask Bottom")
		(17 "Dwgs.User" user "User.Drawings")
		(19 "Cmts.User" user "User.Comments")
		(21 "Eco1.User" user "User.Eco1")
		(23 "Eco2.User" user "User.Eco2")
		(25 "Edge.Cuts" user "Board Geometry/Outline")
		(27 "Margin" user)
		(31 "F.CrtYd" user "Package Geometry/Place Bound Top")
		(29 "B.CrtYd" user "Package Geometry/Place Bound Bottom")
		(35 "F.Fab" user "Ref Des/Assembly Top")
		(33 "B.Fab" user "Ref Des/Assembly Bottom")
	)
	(footprint ""
		(layer "F.Cu")
		(at 423.506646 -48.968152)
		(property "Reference" "R25W104"
			(at -0.8382 -0.67818 0)
			(unlocked yes)
			(layer "F.SilkS")
			(effects
				(font
					(size 0.4064 0.254)
					(thickness 0.1524)
				)
				(justify left)
			)
		)
		(property "Value" ""
			(at 0 0 0)
			(layer "F.Fab")
			(effects
				(font
					(size 1.27 1.27)
				)
			)
		)
		(duplicate_pad_numbers_are_jumpers no)
		(fp_poly
			(pts
				(xy -0.2794 -0.1016) (xy 0.2794 -0.1016) (xy 0.2794 0.9906) (xy -0.2794 0.9906)
			)
			(stroke
				(width 0)
				(type default)
			)
			(fill no)
			(layer "F.CrtYd")
		)
		(fp_line
			(start -0.2794 -0.1016)
			(end -0.2794 0.9906)
			(stroke
				(width 0.1)
				(type default)
			)
			(layer "F.Fab")
		)
		(fp_line
			(start -0.2794 0.9906)
			(end 0.2794 0.9906)
			(stroke
				(width 0.1)
				(type default)
			)
			(layer "F.Fab")
		)
		(fp_line
			(start 0.2794 -0.1016)
			(end -0.2794 -0.1016)
			(stroke
				(width 0.1)
				(type default)
			)
			(layer "F.Fab")
		)
		(fp_line
			(start 0.2794 0.9906)
			(end 0.2794 -0.1016)
			(stroke
				(width 0.1)
				(type default)
			)
			(layer "F.Fab")
		)
		(pad "1" smd rect
			(at 0 0)
			(size 0.508 0.508)
			(layers "F.Cu" "F.Mask" "F.Paste")
			(net "P3V3_STBY")
		)
		(pad "2" smd rect
			(at 0 0.889)
			(size 0.508 0.508)
			(layers "F.Cu" "F.Mask" "F.Paste")
			(net "BMC_STRAP_BIT27")
		)
		(zone
			(layer "F.Cu")
			(hatch none 0.5)
			(connect_pads
				(clearance 0)
			)
			(min_thickness 0.25)
			(keepout
				(tracks allowed)
				(vias not_allowed)
				(pads allowed)
				(copperpour not_allowed)
				(footprints allowed)
			)
			(placement
				(enabled no)
				(sheetname "")
			)
			(fill
				(thermal_gap 0.5)
				(thermal_bridge_width 0.5)
				(island_removal_mode 0)
			)
			(polygon
				(pts
					(xy 423.252646 -48.714152) (xy 423.760646 -48.714152) (xy 423.760646 -48.333152) (xy 423.252646 -48.333152)
				)
			)
		)
		(zone
			(layer "F.Cu")
			(hatch none 0.5)
			(connect_pads
				(clearance 0)
			)
			(min_thickness 0.25)
			(keepout
				(tracks not_allowed)
				(vias allowed)
				(pads allowed)
				(copperpour not_allowed)
				(footprints allowed)
			)
			(placement
				(enabled no)
				(sheetname "")
			)
			(fill
				(thermal_gap 0.5)
				(thermal_bridge_width 0.5)
				(island_removal_mode 0)
			)
			(polygon
				(pts
					(xy 423.252646 -48.333152) (xy 423.760646 -48.333152) (xy 423.760646 -48.714152) (xy 423.252646 -48.714152)
				)
			)
		)
	)
	(footprint ""
		(layer "F.Cu")
		(at 164.211 -68.1482 90)
		(property "Reference" "R4D54"
			(at 0 0 90)
			(layer "F.SilkS")
			(hide yes)
			(effects
				(font
					(size 1.27 1.27)
				)
			)
		)
		(property "Value" ""
			(at 0 0 90)
			(layer "F.Fab")
			(effects
				(font
					(size 1.27 1.27)
				)
			)
		)
		(duplicate_pad_numbers_are_jumpers no)
		(fp_poly
			(pts
				(xy -0.2794 -0.1016) (xy 0.2794 -0.1016) (xy 0.2794 0.9906) (xy -0.2794 0.9906)
			)
			(stroke
				(width 0)
				(type default)
			)
			(fill no)
			(layer "F.CrtYd")
		)
		(fp_line
			(start 0.2794 -0.1016)
			(end -0.2794 -0.1016)
			(stroke
				(width 0.1)
				(type default)
			)
			(layer "F.Fab")
		)
		(fp_line
			(start -0.2794 -0.1016)
			(end -0.2794 0.9906)
			(stroke
				(width 0.1)
				(type default)
			)
			(layer "F.Fab")
		)
		(fp_line
			(start 0.2794 0.9906)
			(end 0.2794 -0.1016)
			(stroke
				(width 0.1)
				(type default)
			)
			(layer "F.Fab")
		)
		(fp_line
			(start -0.2794 0.9906)
			(end 0.2794 0.9906)
			(stroke
				(width 0.1)
				(type default)
			)
			(layer "F.Fab")
		)
		(pad "1" smd rect
			(at 0 0 90)
			(size 0.508 0.508)
			(layers "F.Cu" "F.Mask" "F.Paste")
			(net "SVID_DIO0_CPU1_R")
		)
		(pad "2" smd rect
			(at 0 0.889 90)
			(size 0.508 0.508)
			(layers "F.Cu" "F.Mask" "F.Paste")
			(net "SVID_VDIO_PVCCIO_CPU1")
		)
		(zone
			(layer "F.Cu")
			(hatch none 0.5)
			(connect_pads
				(clearance 0)
			)
			(min_thickness 0.25)
			(keepout
				(tracks allowed)
				(vias not_allowed)
				(pads allowed)
				(copperpour not_allowed)
				(footprints allowed)
			)
			(placement
				(enabled no)
				(sheetname "")
			)
			(fill
				(thermal_gap 0.5)
				(thermal_bridge_width 0.5)
				(island_removal_mode 0)
			)
			(polygon
				(pts
					(xy 164.465 -67.8942) (xy 164.465 -68.4022) (xy 164.846 -68.4022) (xy 164.846 -67.8942)
				)
			)
		)
		(zone
			(layer "F.Cu")
			(hatch none 0.5)
			(connect_pads
				(clearance 0)
			)
			(min_thickness 0.25)
			(keepout
				(tracks not_allowed)
				(vias allowed)
				(pads allowed)
				(copperpour not_allowed)
				(footprints allowed)
			)
			(placement
				(enabled no)
				(sheetname "")
			)
			(fill
				(thermal_gap 0.5)
				(thermal_bridge_width 0.5)
				(island_removal_mode 0)
			)
			(polygon
				(pts
					(xy 164.846 -67.8942) (xy 164.846 -68.4022) (xy 164.465 -68.4022) (xy 164.465 -67.8942)
				)
			)
		)
	)
	(footprint ""
		(layer "F.Cu")
		(at 192.6463 -82.209132 90)
		(property "Reference" "RT28"
			(at 1.01473 0.656336 0)
			(unlocked yes)
			(layer "F.SilkS")
			(effects
				(font
					(size 0.4064 0.254)
					(thickness 0.1524)
				)
			)
		)
		(property "Value" ""
			(at 0 0 90)
			(layer "F.Fab")
			(effects
				(font
					(size 1.27 1.27)
				)
			)
		)
		(duplicate_pad_numbers_are_jumpers no)
		(fp_poly
			(pts
				(xy -0.4953 -0.2032) (xy 0.4953 -0.2032) (xy 0.4953 1.6002) (xy -0.4953 1.6002)
			)
			(stroke
				(width 0)
				(type default)
			)
			(fill no)
			(layer "F.CrtYd")
		)
		(fp_line
			(start 0.4953 -0.2032)
			(end 0.4953 1.6002)
			(stroke
				(width 0.1)
				(type default)
			)
			(layer "F.Fab")
		)
		(fp_line
			(start -0.4953 -0.2032)
			(end 0.4953 -0.2032)
			(stroke
				(width 0.1)
				(type default)
			)
			(layer "F.Fab")
		)
		(fp_line
			(start 0.4953 1.6002)
			(end -0.4953 1.6002)
			(stroke
				(width 0.1)
				(type default)
			)
			(layer "F.Fab")
		)
		(fp_line
			(start -0.4953 1.6002)
			(end -0.4953 -0.2032)
			(stroke
				(width 0.1)
				(type default)
			)
			(layer "F.Fab")
		)
		(pad "1" smd rect
			(at 0 0 90)
			(size 0.762 0.889)
			(layers "F.Cu" "F.Mask" "F.Paste")
			(net "VR_PVCCIN_CPU0_PH4_BOOT")
		)
		(pad "2" smd rect
			(at 0 1.397 90)
			(size 0.762 0.889)
			(layers "F.Cu" "F.Mask" "F.Paste")
			(net "VR_PVCCIN_CPU0_PH4_BOOT_R")
		)
		(zone
			(layer "F.Cu")
			(hatch none 0.5)
			(connect_pads
				(clearance 0)
			)
			(min_thickness 0.25)
			(keepout
				(tracks allowed)
				(vias not_allowed)
				(pads allowed)
				(copperpour not_allowed)
				(footprints allowed)
			)
			(placement
				(enabled no)
				(sheetname "")
			)
			(fill
				(thermal_gap 0.5)
				(thermal_bridge_width 0.5)
				(island_removal_mode 0)
			)
			(polygon
				(pts
					(xy 193.5988 -82.590132) (xy 193.0908 -82.590132) (xy 193.0908 -81.828132) (xy 193.5988 -81.828132)
				)
			)
		)
		(zone
			(layer "F.Cu")
			(hatch none 0.5)
			(connect_pads
				(clearance 0)
			)
			(min_thickness 0.25)
			(keepout
				(tracks not_allowed)
				(vias allowed)
				(pads allowed)
				(copperpour not_allowed)
				(footprints allowed)
			)
			(placement
				(enabled no)
				(sheetname "")
			)
			(fill
				(thermal_gap 0.5)
				(thermal_bridge_width 0.5)
				(island_removal_mode 0)
			)
			(polygon
				(pts
					(xy 193.5988 -81.828132) (xy 193.5988 -82.590132) (xy 193.0908 -82.590132) (xy 193.0908 -81.828132)
				)
			)
		)
	)
)
